(kicad_pcb
	(version 20260206)
	(generator "pcbnew")
	(generator_version "10.0")
	(general
		(thickness 1.6)
		(legacy_teardrops no)
	)
	(paper "A4")
	(title_block
		(title "04192023_DAF0TMB3IC0_F0TG_MB_C_brd_V02_OCP.brd")
		(comment 1 "Grand Teton / footprints 5045-5050 of 8354")
	)
	(layers
		(0 "F.Cu" signal "TOP")
		(4 "In1.Cu" signal "GND")
		(6 "In2.Cu" signal "IN1")
		(8 "In3.Cu" signal "GND1")
		(10 "In4.Cu" signal "IN2")
		(12 "In5.Cu" signal "GND2")
		(14 "In6.Cu" signal "IN3")
		(16 "In7.Cu" signal "GND3")
		(18 "In8.Cu" signal "VCC")
		(20 "In9.Cu" signal "VCC1")
		(22 "In10.Cu" signal "GND4")
		(24 "In11.Cu" signal "IN4")
		(26 "In12.Cu" signal "GND5")
		(28 "In13.Cu" signal "IN5")
		(30 "In14.Cu" signal "GND6")
		(32 "In15.Cu" signal "IN6")
		(34 "In16.Cu" signal "GND7")
		(2 "B.Cu" signal "BOTTOM")
		(9 "F.Adhes" user "F.Adhesive")
		(11 "B.Adhes" user "B.Adhesive")
		(13 "F.Paste" user "Package Geometry/Pastemask Top")
		(15 "B.Paste" user "Package Geometry/Pastemask Bottom")
		(5 "F.SilkS" user "Ref Des/Silkscreen Top")
		(7 "B.SilkS" user "Ref Des/Silkscreen Bottom")
		(1 "F.Mask" user "Board Geometry/Soldermask Top")
		(3 "B.Mask" user "Board Geometry/Soldermask Bottom")
		(17 "Dwgs.User" user "User.Drawings")
		(19 "Cmts.User" user "User.Comments")
		(21 "Eco1.User" user "User.Eco1")
		(23 "Eco2.User" user "User.Eco2")
		(25 "Edge.Cuts" user "Board Geometry/Outline")
		(27 "Margin" user)
		(31 "F.CrtYd" user "Package Geometry/Place Bound Top")
		(29 "B.CrtYd" user "Package Geometry/Place Bound Bottom")
		(35 "F.Fab" user "Ref Des/Assembly Top")
		(33 "B.Fab" user "Ref Des/Assembly Bottom")
	)
	(footprint ""
		(layer "B.Cu")
		(at 317.791084 -398.942052 90)
		(property "Reference" "C584"
			(at 0 0 90)
			(layer "B.SilkS")
			(hide yes)
			(effects
				(font
					(size 1.27 1.27)
				)
				(justify mirror)
			)
		)
		(property "Value" ""
			(at 0 0 90)
			(layer "B.Fab")
			(effects
				(font
					(size 1.27 1.27)
				)
				(justify mirror)
			)
		)
		(duplicate_pad_numbers_are_jumpers no)
		(fp_line
			(start 0.7874 -0.4064)
			(end -0.7874 -0.4064)
			(stroke
				(width 0.1524)
				(type default)
			)
			(layer "B.SilkS")
		)
		(fp_line
			(start -0.7874 -0.4064)
			(end -0.7874 0.4064)
			(stroke
				(width 0.1524)
				(type default)
			)
			(layer "B.SilkS")
		)
		(fp_line
			(start 0.7874 0.4064)
			(end 0.7874 -0.4064)
			(stroke
				(width 0.1524)
				(type default)
			)
			(layer "B.SilkS")
		)
		(fp_line
			(start -0.7874 0.4064)
			(end 0.7874 0.4064)
			(stroke
				(width 0.1524)
				(type default)
			)
			(layer "B.SilkS")
		)
		(fp_line
			(start 0.67945 -0.305054)
			(end 0.12065 -0.305054)
			(stroke
				(width 0.1)
				(type default)
			)
			(layer "B.Fab")
		)
		(fp_line
			(start 0.12065 -0.305054)
			(end 0.12065 -0.2794)
			(stroke
				(width 0.1)
				(type default)
			)
			(layer "B.Fab")
		)
		(fp_line
			(start -0.12065 -0.3048)
			(end -0.67945 -0.3048)
			(stroke
				(width 0.1)
				(type default)
			)
			(layer "B.Fab")
		)
		(fp_line
			(start -0.67945 -0.3048)
			(end -0.67945 0.3048)
			(stroke
				(width 0.1)
				(type default)
			)
			(layer "B.Fab")
		)
		(fp_line
			(start 0.12065 -0.2794)
			(end -0.12065 -0.2794)
			(stroke
				(width 0.1)
				(type default)
			)
			(layer "B.Fab")
		)
		(fp_line
			(start -0.12065 -0.2794)
			(end -0.12065 -0.3048)
			(stroke
				(width 0.1)
				(type default)
			)
			(layer "B.Fab")
		)
		(fp_line
			(start 0.12065 0.2794)
			(end 0.12065 0.3048)
			(stroke
				(width 0.1)
				(type default)
			)
			(layer "B.Fab")
		)
		(fp_line
			(start -0.120396 0.2794)
			(end 0.12065 0.2794)
			(stroke
				(width 0.1)
				(type default)
			)
			(layer "B.Fab")
		)
		(fp_line
			(start 0.67945 0.3048)
			(end 0.67945 -0.305054)
			(stroke
				(width 0.1)
				(type default)
			)
			(layer "B.Fab")
		)
		(fp_line
			(start 0.12065 0.3048)
			(end 0.67945 0.3048)
			(stroke
				(width 0.1)
				(type default)
			)
			(layer "B.Fab")
		)
		(fp_line
			(start -0.120396 0.3048)
			(end -0.120396 0.2794)
			(stroke
				(width 0.1)
				(type default)
			)
			(layer "B.Fab")
		)
		(fp_line
			(start -0.67945 0.3048)
			(end -0.120396 0.3048)
			(stroke
				(width 0.1)
				(type default)
			)
			(layer "B.Fab")
		)
		(pad "1" smd circle
			(at 0.40005 0 270)
			(size 0 0)
			(layers "B.Cu" "B.Mask" "B.Paste")
			(net "P0V9_CPU0_RT0_2A")
		)
		(pad "2" smd circle
			(at -0.40005 0 270)
			(size 0 0)
			(layers "B.Cu" "B.Mask" "B.Paste")
			(net "GND")
		)
	)
	(footprint ""
		(layer "B.Cu")
		(at 392.118088 -314.172854 90)
		(property "Reference" "R740"
			(at 0 0 90)
			(layer "B.SilkS")
			(hide yes)
			(effects
				(font
					(size 1.27 1.27)
				)
				(justify mirror)
			)
		)
		(property "Value" ""
			(at 0 0 90)
			(layer "B.Fab")
			(effects
				(font
					(size 1.27 1.27)
				)
				(justify mirror)
			)
		)
		(duplicate_pad_numbers_are_jumpers no)
		(fp_line
			(start 0.7874 -0.4064)
			(end -0.7874 -0.4064)
			(stroke
				(width 0.1524)
				(type default)
			)
			(layer "B.SilkS")
		)
		(fp_line
			(start -0.7874 -0.4064)
			(end -0.7874 0.4064)
			(stroke
				(width 0.1524)
				(type default)
			)
			(layer "B.SilkS")
		)
		(fp_line
			(start 0.7874 0.4064)
			(end 0.7874 -0.4064)
			(stroke
				(width 0.1524)
				(type default)
			)
			(layer "B.SilkS")
		)
		(fp_line
			(start -0.7874 0.4064)
			(end 0.7874 0.4064)
			(stroke
				(width 0.1524)
				(type default)
			)
			(layer "B.SilkS")
		)
		(fp_line
			(start 0.67945 -0.305054)
			(end 0.12065 -0.305054)
			(stroke
				(width 0.1)
				(type default)
			)
			(layer "B.Fab")
		)
		(fp_line
			(start 0.12065 -0.305054)
			(end 0.12065 -0.2794)
			(stroke
				(width 0.1)
				(type default)
			)
			(layer "B.Fab")
		)
		(fp_line
			(start -0.12065 -0.3048)
			(end -0.67945 -0.3048)
			(stroke
				(width 0.1)
				(type default)
			)
			(layer "B.Fab")
		)
		(fp_line
			(start -0.67945 -0.3048)
			(end -0.67945 0.3048)
			(stroke
				(width 0.1)
				(type default)
			)
			(layer "B.Fab")
		)
		(fp_line
			(start 0.12065 -0.2794)
			(end -0.12065 -0.2794)
			(stroke
				(width 0.1)
				(type default)
			)
			(layer "B.Fab")
		)
		(fp_line
			(start -0.12065 -0.2794)
			(end -0.12065 -0.3048)
			(stroke
				(width 0.1)
				(type default)
			)
			(layer "B.Fab")
		)
		(fp_line
			(start 0.12065 0.2794)
			(end 0.12065 0.3048)
			(stroke
				(width 0.1)
				(type default)
			)
			(layer "B.Fab")
		)
		(fp_line
			(start -0.120396 0.2794)
			(end 0.12065 0.2794)
			(stroke
				(width 0.1)
				(type default)
			)
			(layer "B.Fab")
		)
		(fp_line
			(start 0.67945 0.3048)
			(end 0.67945 -0.305054)
			(stroke
				(width 0.1)
				(type default)
			)
			(layer "B.Fab")
		)
		(fp_line
			(start 0.12065 0.3048)
			(end 0.67945 0.3048)
			(stroke
				(width 0.1)
				(type default)
			)
			(layer "B.Fab")
		)
		(fp_line
			(start -0.120396 0.3048)
			(end -0.120396 0.2794)
			(stroke
				(width 0.1)
				(type default)
			)
			(layer "B.Fab")
		)
		(fp_line
			(start -0.67945 0.3048)
			(end -0.120396 0.3048)
			(stroke
				(width 0.1)
				(type default)
			)
			(layer "B.Fab")
		)
		(pad "1" smd circle
			(at 0.40005 0 270)
			(size 0 0)
			(layers "B.Cu" "B.Mask" "B.Paste")
			(net "PVDD18_S5_P0")
		)
		(pad "2" smd circle
			(at -0.40005 0 270)
			(size 0 0)
			(layers "B.Cu" "B.Mask" "B.Paste")
			(net "CLK_CPU0_RTCCLK")
		)
	)
	(footprint ""
		(layer "B.Cu")
		(at 153.018998 -390.560052 90)
		(property "Reference" "C419"
			(at 0 0 90)
			(layer "B.SilkS")
			(hide yes)
			(effects
				(font
					(size 1.27 1.27)
				)
				(justify mirror)
			)
		)
		(property "Value" ""
			(at 0 0 90)
			(layer "B.Fab")
			(effects
				(font
					(size 1.27 1.27)
				)
				(justify mirror)
			)
		)
		(duplicate_pad_numbers_are_jumpers no)
		(fp_line
			(start 0.7874 -0.4064)
			(end -0.7874 -0.4064)
			(stroke
				(width 0.1524)
				(type default)
			)
			(layer "B.SilkS")
		)
		(fp_line
			(start -0.7874 -0.4064)
			(end -0.7874 0.4064)
			(stroke
				(width 0.1524)
				(type default)
			)
			(layer "B.SilkS")
		)
		(fp_line
			(start 0.7874 0.4064)
			(end 0.7874 -0.4064)
			(stroke
				(width 0.1524)
				(type default)
			)
			(layer "B.SilkS")
		)
		(fp_line
			(start -0.7874 0.4064)
			(end 0.7874 0.4064)
			(stroke
				(width 0.1524)
				(type default)
			)
			(layer "B.SilkS")
		)
		(fp_line
			(start 0.67945 -0.305054)
			(end 0.12065 -0.305054)
			(stroke
				(width 0.1)
				(type default)
			)
			(layer "B.Fab")
		)
		(fp_line
			(start 0.12065 -0.305054)
			(end 0.12065 -0.2794)
			(stroke
				(width 0.1)
				(type default)
			)
			(layer "B.Fab")
		)
		(fp_line
			(start -0.12065 -0.3048)
			(end -0.67945 -0.3048)
			(stroke
				(width 0.1)
				(type default)
			)
			(layer "B.Fab")
		)
		(fp_line
			(start -0.67945 -0.3048)
			(end -0.67945 0.3048)
			(stroke
				(width 0.1)
				(type default)
			)
			(layer "B.Fab")
		)
		(fp_line
			(start 0.12065 -0.2794)
			(end -0.12065 -0.2794)
			(stroke
				(width 0.1)
				(type default)
			)
			(layer "B.Fab")
		)
		(fp_line
			(start -0.12065 -0.2794)
			(end -0.12065 -0.3048)
			(stroke
				(width 0.1)
				(type default)
			)
			(layer "B.Fab")
		)
		(fp_line
			(start 0.12065 0.2794)
			(end 0.12065 0.3048)
			(stroke
				(width 0.1)
				(type default)
			)
			(layer "B.Fab")
		)
		(fp_line
			(start -0.120396 0.2794)
			(end 0.12065 0.2794)
			(stroke
				(width 0.1)
				(type default)
			)
			(layer "B.Fab")
		)
		(fp_line
			(start 0.67945 0.3048)
			(end 0.67945 -0.305054)
			(stroke
				(width 0.1)
				(type default)
			)
			(layer "B.Fab")
		)
		(fp_line
			(start 0.12065 0.3048)
			(end 0.67945 0.3048)
			(stroke
				(width 0.1)
				(type default)
			)
			(layer "B.Fab")
		)
		(fp_line
			(start -0.120396 0.3048)
			(end -0.120396 0.2794)
			(stroke
				(width 0.1)
				(type default)
			)
			(layer "B.Fab")
		)
		(fp_line
			(start -0.67945 0.3048)
			(end -0.120396 0.3048)
			(stroke
				(width 0.1)
				(type default)
			)
			(layer "B.Fab")
		)
		(pad "1" smd circle
			(at 0.40005 0 270)
			(size 0 0)
			(layers "B.Cu" "B.Mask" "B.Paste")
			(net "P0V9_CPU1_RT_2D")
		)
		(pad "2" smd circle
			(at -0.40005 0 270)
			(size 0 0)
			(layers "B.Cu" "B.Mask" "B.Paste")
			(net "GND")
		)
	)
	(footprint ""
		(layer "B.Cu")
		(at 167.502332 -431.326544 180)
		(property "Reference" "Q131"
			(at -6.290056 0.352552 0)
			(unlocked yes)
			(layer "B.SilkS")
			(effects
				(font
					(size 0.7874 0.5842)
					(thickness 0.1524)
				)
				(justify left mirror)
			)
		)
		(property "Value" ""
			(at 0 0 0)
			(layer "B.Fab")
			(effects
				(font
					(size 1.27 1.27)
				)
				(justify mirror)
			)
		)
		(duplicate_pad_numbers_are_jumpers no)
		(fp_line
			(start 1.332738 1.100074)
			(end 1.332738 -1.100074)
			(stroke
				(width 0.1524)
				(type default)
			)
			(layer "B.SilkS")
		)
		(fp_line
			(start 1.332738 -1.100074)
			(end 0.4826 -1.100074)
			(stroke
				(width 0.1524)
				(type default)
			)
			(layer "B.SilkS")
		)
		(fp_line
			(start 0.4826 -1.100074)
			(end 0 -0.541274)
			(stroke
				(width 0.1524)
				(type default)
			)
			(layer "B.SilkS")
		)
		(fp_line
			(start 0 -0.541274)
			(end -0.4826 -1.100074)
			(stroke
				(width 0.1524)
				(type default)
			)
			(layer "B.SilkS")
		)
		(fp_line
			(start -0.4826 -1.100074)
			(end -1.332738 -1.100074)
			(stroke
				(width 0.1524)
				(type default)
			)
			(layer "B.SilkS")
		)
		(fp_line
			(start -1.332738 1.100074)
			(end 1.332738 1.100074)
			(stroke
				(width 0.1524)
				(type default)
			)
			(layer "B.SilkS")
		)
		(fp_line
			(start -1.332738 -1.100074)
			(end -1.332738 1.100074)
			(stroke
				(width 0.1524)
				(type default)
			)
			(layer "B.SilkS")
		)
		(fp_poly
			(pts
				(xy 1.362456 -1.189482) (xy 2.10693 -1.43764) (xy 1.610614 -1.933956)
			)
			(stroke
				(width 0)
				(type default)
			)
			(fill yes)
			(layer "B.SilkS")
		)
		(fp_line
			(start 0.674878 1.100074)
			(end 0.674878 -1.100074)
			(stroke
				(width 0.1)
				(type default)
			)
			(layer "B.Fab")
		)
		(fp_line
			(start 0.674878 -1.100074)
			(end -0.674878 -1.100074)
			(stroke
				(width 0.1)
				(type default)
			)
			(layer "B.Fab")
		)
		(fp_line
			(start -0.674878 1.100074)
			(end 0.674878 1.100074)
			(stroke
				(width 0.1)
				(type default)
			)
			(layer "B.Fab")
		)
		(fp_line
			(start -0.674878 -1.100074)
			(end -0.674878 1.100074)
			(stroke
				(width 0.1)
				(type default)
			)
			(layer "B.Fab")
		)
		(fp_poly
			(pts
				(xy 2.2352 -0.298958) (xy 2.2352 -1.001014) (xy 1.533144 -0.649986)
			)
			(stroke
				(width 0)
				(type default)
			)
			(fill yes)
			(layer "B.Fab")
		)
		(pad "1" smd rect
			(at 0.94996 -0.649986 270)
			(size 0.4318 0.508)
			(layers "B.Cu" "B.Mask" "B.Paste")
			(net "GND")
		)
		(pad "2" smd rect
			(at 0.94996 0 270)
			(size 0.4318 0.508)
			(layers "B.Cu" "B.Mask" "B.Paste")
			(net "GPU_3V3IO_RSVD1_FFU")
		)
		(pad "3" smd rect
			(at 0.94996 0.649986 270)
			(size 0.4318 0.508)
			(layers "B.Cu" "B.Mask" "B.Paste")
			(net "GPU_3V3IO_RSVD1_FFU_ISO")
		)
		(pad "4" smd rect
			(at -0.94996 0.649986 270)
			(size 0.4318 0.508)
			(layers "B.Cu" "B.Mask" "B.Paste")
			(net "GND")
		)
		(pad "5" smd rect
			(at -0.94996 0 270)
			(size 0.4318 0.508)
			(layers "B.Cu" "B.Mask" "B.Paste")
			(net "GPU_3V3IO_RSVD1_FFU_N")
		)
		(pad "6" smd rect
			(at -0.94996 -0.649986 270)
			(size 0.4318 0.508)
			(layers "B.Cu" "B.Mask" "B.Paste")
			(net "GPU_3V3IO_RSVD1_FFU_N")
		)
	)
	(footprint ""
		(layer "B.Cu")
		(at 47.784004 -192.66027 180)
		(property "Reference" "C175"
			(at 0 0 0)
			(layer "B.SilkS")
			(hide yes)
			(effects
				(font
					(size 1.27 1.27)
				)
				(justify mirror)
			)
		)
		(property "Value" ""
			(at 0 0 0)
			(layer "B.Fab")
			(effects
				(font
					(size 1.27 1.27)
				)
				(justify mirror)
			)
		)
		(duplicate_pad_numbers_are_jumpers no)
		(fp_line
			(start 1.524 0.762)
			(end 1.524 -0.762)
			(stroke
				(width 0.1524)
				(type default)
			)
			(layer "B.SilkS")
		)
		(fp_line
			(start 1.524 -0.762)
			(end -1.524 -0.762)
			(stroke
				(width 0.1524)
				(type default)
			)
			(layer "B.SilkS")
		)
		(fp_line
			(start -1.524 0.762)
			(end 1.524 0.762)
			(stroke
				(width 0.1524)
				(type default)
			)
			(layer "B.SilkS")
		)
		(fp_line
			(start -1.524 -0.762)
			(end -1.524 0.762)
			(stroke
				(width 0.1524)
				(type default)
			)
			(layer "B.SilkS")
		)
		(fp_line
			(start 1.1049 0.724916)
			(end -1.1049 0.724916)
			(stroke
				(width 0.1)
				(type default)
			)
			(layer "B.Fab")
		)
		(fp_line
			(start 1.1049 -0.724916)
			(end 1.1049 0.724916)
			(stroke
				(width 0.1)
				(type default)
			)
			(layer "B.Fab")
		)
		(fp_line
			(start -1.1049 0.724916)
			(end -1.1049 -0.724916)
			(stroke
				(width 0.1)
				(type default)
			)
			(layer "B.Fab")
		)
		(fp_line
			(start -1.1049 -0.724916)
			(end 1.1049 -0.724916)
			(stroke
				(width 0.1)
				(type default)
			)
			(layer "B.Fab")
		)
		(pad "1" smd rect
			(at 0.889 0 180)
			(size 1.016 1.27)
			(layers "B.Cu" "B.Mask" "B.Paste")
			(net "P12V_MEM_CPU1")
		)
		(pad "2" smd rect
			(at -0.889 0 180)
			(size 1.016 1.27)
			(layers "B.Cu" "B.Mask" "B.Paste")
			(net "GND")
		)
	)
	(footprint ""
		(layer "B.Cu")
		(at 374.487186 -214.523828 90)
		(property "Reference" "R9273"
			(at 0 0 90)
			(layer "B.SilkS")
			(hide yes)
			(effects
				(font
					(size 1.27 1.27)
				)
				(justify mirror)
			)
		)
		(property "Value" ""
			(at 0 0 90)
			(layer "B.Fab")
			(effects
				(font
					(size 1.27 1.27)
				)
				(justify mirror)
			)
		)
		(duplicate_pad_numbers_are_jumpers no)
		(fp_line
			(start 0.436372 -0.4064)
			(end -0.351028 -0.4064)
			(stroke
				(width 0.1524)
				(type default)
			)
			(layer "B.SilkS")
		)
		(fp_line
			(start -0.7874 0.035814)
			(end -0.7874 0.4064)
			(stroke
				(width 0.1524)
				(type default)
			)
			(layer "B.SilkS")
		)
		(fp_line
			(start 0.7874 0.4064)
			(end 0.7874 -0.014986)
			(stroke
				(width 0.1524)
				(type default)
			)
			(layer "B.SilkS")
		)
		(fp_line
			(start -0.7874 0.4064)
			(end 0.7874 0.4064)
			(stroke
				(width 0.1524)
				(type default)
			)
			(layer "B.SilkS")
		)
		(fp_line
			(start 0.67945 -0.305054)
			(end 0.12065 -0.305054)
			(stroke
				(width 0.1)
				(type default)
			)
			(layer "B.Fab")
		)
		(fp_line
			(start 0.12065 -0.305054)
			(end 0.12065 -0.2794)
			(stroke
				(width 0.1)
				(type default)
			)
			(layer "B.Fab")
		)
		(fp_line
			(start -0.12065 -0.3048)
			(end -0.67945 -0.3048)
			(stroke
				(width 0.1)
				(type default)
			)
			(layer "B.Fab")
		)
		(fp_line
			(start -0.67945 -0.3048)
			(end -0.67945 0.3048)
			(stroke
				(width 0.1)
				(type default)
			)
			(layer "B.Fab")
		)
		(fp_line
			(start 0.12065 -0.2794)
			(end -0.12065 -0.2794)
			(stroke
				(width 0.1)
				(type default)
			)
			(layer "B.Fab")
		)
		(fp_line
			(start -0.12065 -0.2794)
			(end -0.12065 -0.3048)
			(stroke
				(width 0.1)
				(type default)
			)
			(layer "B.Fab")
		)
		(fp_line
			(start 0.12065 0.2794)
			(end 0.12065 0.3048)
			(stroke
				(width 0.1)
				(type default)
			)
			(layer "B.Fab")
		)
		(fp_line
			(start -0.120396 0.2794)
			(end 0.12065 0.2794)
			(stroke
				(width 0.1)
				(type default)
			)
			(layer "B.Fab")
		)
		(fp_line
			(start 0.67945 0.3048)
			(end 0.67945 -0.305054)
			(stroke
				(width 0.1)
				(type default)
			)
			(layer "B.Fab")
		)
		(fp_line
			(start 0.12065 0.3048)
			(end 0.67945 0.3048)
			(stroke
				(width 0.1)
				(type default)
			)
			(layer "B.Fab")
		)
		(fp_line
			(start -0.120396 0.3048)
			(end -0.120396 0.2794)
			(stroke
				(width 0.1)
				(type default)
			)
			(layer "B.Fab")
		)
		(fp_line
			(start -0.67945 0.3048)
			(end -0.120396 0.3048)
			(stroke
				(width 0.1)
				(type default)
			)
			(layer "B.Fab")
		)
		(pad "1" smd circle
			(at 0.40005 0 270)
			(size 0 0)
			(layers "B.Cu" "B.Mask" "B.Paste")
			(net "CLK_100M_CPU0_CLK04_R_DP")
		)
		(pad "2" smd circle
			(at -0.40005 0 270)
			(size 0 0)
			(layers "B.Cu" "B.Mask" "B.Paste")
			(net "CLK_100M_CPU0_CLK04_DP")
		)
	)
)
